(kicad_pcb
	(version 20241229)
	(generator "pcbnew")
	(generator_version "9.0")
	(general
		(thickness 1.6642)
		(legacy_teardrops no)
	)
	(paper "A3")
	(title_block
		(title "PolarFire SoM")
		(date "2025-07-22")
		(rev "1.1.4")
		(company "Antmicro Ltd")
		(comment 1 "www.antmicro.com")
		(comment 9 "footprints 371-373 of 470")
	)
	(layers
		(0 "F.Cu" mixed)
		(4 "In1.Cu" power)
		(6 "In2.Cu" signal)
		(8 "In3.Cu" power)
		(10 "In4.Cu" signal)
		(12 "In5.Cu" power)
		(14 "In6.Cu" power)
		(16 "In7.Cu" signal)
		(18 "In8.Cu" power)
		(20 "In9.Cu" signal)
		(22 "In10.Cu" power)
		(24 "In11.Cu" signal)
		(26 "In12.Cu" signal)
		(2 "B.Cu" mixed)
		(9 "F.Adhes" user "F.Adhesive")
		(11 "B.Adhes" user "B.Adhesive")
		(13 "F.Paste" user)
		(15 "B.Paste" user)
		(5 "F.SilkS" user "F.Silkscreen")
		(7 "B.SilkS" user "B.Silkscreen")
		(1 "F.Mask" user)
		(3 "B.Mask" user)
		(17 "Dwgs.User" user "User.Drawings")
		(19 "Cmts.User" user "User.Comments")
		(21 "Eco1.User" user "User.Eco1")
		(23 "Eco2.User" user "User.Eco2")
		(25 "Edge.Cuts" user)
		(27 "Margin" user)
		(31 "F.CrtYd" user "F.Courtyard")
		(29 "B.CrtYd" user "B.Courtyard")
		(35 "F.Fab" user)
		(33 "B.Fab" user)
	)
	(footprint "antmicro-footprints:SOT-363"
		(layer "B.Cu")
		(at 186.075 152.127 90)
		(property "Reference" "Q3"
			(at 1.317 -1.415 180)
			(layer "B.SilkS")
			(effects
				(font
					(size 0.7 0.7)
					(thickness 0.15)
				)
				(justify right bottom mirror)
			)
		)
		(property "Value" "DZDH0401DW"
			(at 0 -2.2 90)
			(layer "B.Fab")
			(hide yes)
			(effects
				(font
					(size 0.7 0.7)
					(thickness 0.15)
				)
				(justify right bottom mirror)
			)
		)
		(property "Datasheet" "https://www.mouser.com/datasheet/2/115/DIOD_S_A0011803041_1-2543705.pdf"
			(at 0 0 90)
			(layer "F.Fab")
			(hide yes)
			(effects
				(font
					(size 1.27 1.27)
					(thickness 0.15)
				)
			)
		)
		(property "Description" "OR Controller N+1 ORing Controller P-Channel 1:1 SOT-363"
			(at 0 0 90)
			(layer "F.Fab")
			(hide yes)
			(effects
				(font
					(size 1.27 1.27)
					(thickness 0.15)
				)
			)
		)
		(property "Author" "Antmicro"
			(at 338.202 -33.948 0)
			(layer "B.Fab")
			(hide yes)
			(effects
				(font
					(size 1 1)
					(thickness 0.15)
				)
				(justify mirror)
			)
		)
		(property "License" "Apache-2.0"
			(at 338.202 -33.948 0)
			(layer "B.Fab")
			(hide yes)
			(effects
				(font
					(size 1 1)
					(thickness 0.15)
				)
				(justify mirror)
			)
		)
		(property "MPN" "DZDH0401DW"
			(at 338.202 -33.948 0)
			(layer "B.Fab")
			(hide yes)
			(effects
				(font
					(size 1 1)
					(thickness 0.15)
				)
				(justify mirror)
			)
		)
		(property "Manufacturer" "Diodes Incorporated"
			(at 338.202 -33.948 0)
			(layer "B.Fab")
			(hide yes)
			(effects
				(font
					(size 1 1)
					(thickness 0.15)
				)
				(justify mirror)
			)
		)
		(sheetname "/Bottom Connector/")
		(sheetfile "bottom-connector.kicad_sch")
		(attr smd)
		(fp_line
			(start -0.8 -1.223)
			(end 0.803 -1.223)
			(stroke
				(width 0.15)
				(type solid)
			)
			(layer "B.SilkS")
		)
		(fp_line
			(start 0.803 -1.146)
			(end 0.803 -1.223)
			(stroke
				(width 0.15)
				(type solid)
			)
			(layer "B.SilkS")
		)
		(fp_line
			(start -0.8 -1.146)
			(end -0.8 -1.223)
			(stroke
				(width 0.15)
				(type solid)
			)
			(layer "B.SilkS")
		)
		(fp_line
			(start 0.803 1.153)
			(end 0.803 1.228)
			(stroke
				(width 0.15)
				(type solid)
			)
			(layer "B.SilkS")
		)
		(fp_line
			(start -0.72 1.153)
			(end -0.72 1.228)
			(stroke
				(width 0.15)
				(type solid)
			)
			(layer "B.SilkS")
		)
		(fp_line
			(start 0.803 1.228)
			(end -0.72 1.228)
			(stroke
				(width 0.15)
				(type solid)
			)
			(layer "B.SilkS")
		)
		(fp_circle
			(center -0.978102 1.2)
			(end -0.928102 1.2)
			(stroke
				(width 0.15)
				(type solid)
			)
			(fill yes)
			(layer "B.SilkS")
		)
		(fp_rect
			(start 1.3 1.3)
			(end -1.3 -1.3)
			(stroke
				(width 0.05)
				(type solid)
			)
			(fill no)
			(layer "B.CrtYd")
		)
		(fp_line
			(start -0.1 1.1)
			(end -0.68 0.52)
			(stroke
				(width 0.15)
				(type solid)
			)
			(layer "B.Fab")
		)
		(fp_rect
			(start 0.68 -1.1)
			(end -0.68 1.1)
			(stroke
				(width 0.15)
				(type solid)
			)
			(fill no)
			(layer "B.Fab")
		)
		(fp_text user "License: Apache-2.0"
			(at -1.3 -5.2 270)
			(layer "B.Fab")
			(effects
				(font
					(size 0.7 0.7)
					(thickness 0.15)
				)
				(justify left bottom mirror)
			)
		)
		(fp_text user "Author: Antmicro"
			(at -1.3 -6.4 270)
			(layer "B.Fab")
			(effects
				(font
					(size 0.7 0.7)
					(thickness 0.15)
				)
				(justify left bottom mirror)
			)
		)
		(fp_text user "${REFERENCE}"
			(at -1.3 -4 270)
			(layer "B.Fab")
			(effects
				(font
					(size 0.7 0.7)
					(thickness 0.15)
				)
				(justify left bottom mirror)
			)
		)
		(pad "1" smd custom
			(at -0.948 0.752 180)
			(size 0.6 0.6)
			(layers "B.Cu" "B.Mask" "B.Paste")
			(net 653 "unconnected-(Q3-NC-Pad1)")
			(pinfunction "NC")
			(pintype "no_connect")
			(options
				(clearance outline)
				(anchor rect)
			)
			(primitives)
		)
		(pad "2" smd rect
			(at -0.948 0.002 180)
			(size 0.4 0.6)
			(layers "B.Cu" "B.Mask" "B.Paste")
			(net 275 "Net-(Q3-REF)")
			(pinfunction "REF")
			(pintype "input")
		)
		(pad "3" smd custom
			(at -0.948 -0.745 180)
			(size 0.6 0.6)
			(layers "B.Cu" "B.Mask" "B.Paste")
			(net 411 "Net-(Q3-BIAS)")
			(pinfunction "BIAS")
			(pintype "output")
			(options
				(clearance outline)
				(anchor rect)
			)
			(primitives)
		)
		(pad "4" smd custom
			(at 0.951 -0.745 180)
			(size 0.6 0.6)
			(layers "B.Cu" "B.Mask" "B.Paste")
			(net 90 "+5V")
			(pinfunction "S")
			(pintype "power_in")
			(options
				(clearance outline)
				(anchor rect)
			)
			(primitives)
		)
		(pad "5" smd rect
			(at 0.951 0.002 180)
			(size 0.4 0.6)
			(layers "B.Cu" "B.Mask" "B.Paste")
			(net 654 "unconnected-(Q3-NC-Pad5)")
			(pinfunction "NC")
			(pintype "no_connect")
		)
		(pad "6" smd custom
			(at 0.951 0.752 180)
			(size 0.6 0.6)
			(layers "B.Cu" "B.Mask" "B.Paste")
			(net 410 "Net-(Q3-D)")
			(pinfunction "D")
			(pintype "power_in")
			(options
				(clearance outline)
				(anchor rect)
			)
			(primitives)
		)
	)
	(footprint "antmicro-footprints:R_0402_1005Metric"
		(layer "B.Cu")
		(at 182.92 144.97 135)
		(descr "Resistor SMD 0402")
		(tags "resistor SMD 0402")
		(property "Reference" "R98"
			(at -0.749533 1.838478 315)
			(layer "B.SilkS")
			(effects
				(font
					(size 0.7 0.7)
					(thickness 0.15)
				)
				(justify right bottom mirror)
			)
		)
		(property "Value" "R_0R_0402"
			(at -1.011843 -1.772046 135)
			(layer "B.Fab")
			(hide yes)
			(effects
				(font
					(size 0.7 0.7)
					(thickness 0.15)
				)
				(justify right bottom mirror)
			)
		)
		(property "Datasheet" "https://industrial.panasonic.com/cdbs/www-data/pdf/RDA0000/AOA0000C301.pdf"
			(at 0 0 135)
			(layer "F.Fab")
			(hide yes)
			(effects
				(font
					(size 1.27 1.27)
					(thickness 0.15)
				)
			)
		)
		(property "Description" "SMD Chip Resistor, Jumper, 0 ohm, 100 mW, 0402 [1005 Metric], Thick Film, General Purpose"
			(at 0 0 135)
			(layer "F.Fab")
			(hide yes)
			(effects
				(font
					(size 1.27 1.27)
					(thickness 0.15)
				)
			)
		)
		(property "Author" "Antmicro"
			(at 414.773242 118.135298 0)
			(layer "B.Fab")
			(hide yes)
			(effects
				(font
					(size 1 1)
					(thickness 0.15)
				)
				(justify mirror)
			)
		)
		(property "Current" "1A"
			(at 414.773242 118.135298 0)
			(layer "B.Fab")
			(hide yes)
			(effects
				(font
					(size 1 1)
					(thickness 0.15)
				)
				(justify mirror)
			)
		)
		(property "License" "Apache-2.0"
			(at 414.773242 118.135298 0)
			(layer "B.Fab")
			(hide yes)
			(effects
				(font
					(size 1 1)
					(thickness 0.15)
				)
				(justify mirror)
			)
		)
		(property "MPN" "ERJ2GE0R00X"
			(at 414.773242 118.135298 0)
			(layer "B.Fab")
			(hide yes)
			(effects
				(font
					(size 1 1)
					(thickness 0.15)
				)
				(justify mirror)
			)
		)
		(property "Manufacturer" "Panasonic"
			(at 414.773242 118.135298 0)
			(layer "B.Fab")
			(hide yes)
			(effects
				(font
					(size 1 1)
					(thickness 0.15)
				)
				(justify mirror)
			)
		)
		(property "Public" ""
			(at 414.773242 118.135298 0)
			(layer "B.Fab")
			(hide yes)
			(effects
				(font
					(size 1 1)
					(thickness 0.15)
				)
				(justify mirror)
			)
		)
		(property "Tolerance" "~"
			(at 414.773242 118.135298 0)
			(layer "B.Fab")
			(hide yes)
			(effects
				(font
					(size 1 1)
					(thickness 0.15)
				)
				(justify mirror)
			)
		)
		(property "Val" "0R"
			(at 414.773242 118.135298 0)
			(layer "B.Fab")
			(hide yes)
			(effects
				(font
					(size 1 1)
					(thickness 0.15)
				)
				(justify mirror)
			)
		)
		(sheetname "/Supply/")
		(sheetfile "supply.kicad_sch")
		(attr smd)
		(fp_poly
			(pts
				(xy -0.925 0.47) (xy 0.925 0.47) (xy 0.925 -0.47) (xy -0.925 -0.47)
			)
			(stroke
				(width 0.05)
				(type default)
			)
			(fill no)
			(layer "B.CrtYd")
		)
		(fp_poly
			(pts
				(xy -0.5 0.25) (xy 0.5 0.25) (xy 0.5 -0.25) (xy -0.5 -0.25)
			)
			(stroke
				(width 0.15)
				(type solid)
			)
			(fill no)
			(layer "B.Fab")
		)
		(fp_text user "${REFERENCE}"
			(at -0.95 -3.168 315)
			(layer "B.Fab")
			(effects
				(font
					(size 0.7 0.7)
					(thickness 0.15)
				)
				(justify left bottom mirror)
			)
		)
		(fp_text user "License: Apache-2.0"
			(at -0.949999 -5.169 315)
			(layer "B.Fab")
			(effects
				(font
					(size 0.7 0.7)
					(thickness 0.15)
				)
				(justify left bottom mirror)
			)
		)
		(fp_text user "Author: Antmicro"
			(at -0.95 -4.169 315)
			(layer "B.Fab")
			(effects
				(font
					(size 0.7 0.7)
					(thickness 0.15)
				)
				(justify left bottom mirror)
			)
		)
		(pad "1" smd roundrect
			(at -0.48 0 135)
			(size 0.59 0.64)
			(layers "B.Cu" "B.Mask" "B.Paste")
			(roundrect_rratio 0.25)
			(net 409 "/Supply/SENSE4_P")
			(pintype "passive")
		)
		(pad "2" smd roundrect
			(at 0.48 0 135)
			(size 0.59 0.64)
			(layers "B.Cu" "B.Mask" "B.Paste")
			(roundrect_rratio 0.25)
			(net 579 "Net-(U6-SENSE4+)")
			(pintype "passive")
		)
	)
	(footprint "antmicro-footprints:C_Array_0508_1220Metric"
		(layer "B.Cu")
		(at 199.84 142.84)
		(property "Reference" "C171"
			(at -1.35 1.27 90)
			(layer "B.SilkS")
			(effects
				(font
					(size 0.7 0.7)
					(thickness 0.15)
				)
				(justify right bottom mirror)
			)
		)
		(property "Value" "C_4x100nF_0508_1220Metric_array"
			(at 0 -2.8 0)
			(layer "B.Fab")
			(hide yes)
			(effects
				(font
					(size 0.7 0.7)
					(thickness 0.15)
				)
				(justify right bottom mirror)
			)
		)
		(property "Datasheet" "https://spicat.kyocera-avx.com/product/mlcc/chartview/W2A4YC104MAT2A/"
			(at 0 0 0)
			(layer "F.Fab")
			(hide yes)
			(effects
				(font
					(size 1.27 1.27)
					(thickness 0.15)
				)
			)
		)
		(property "Description" "4x0.1µF isolated capacitor array 16 V X7R 0508 (1220 Metric)"
			(at 0 0 0)
			(layer "F.Fab")
			(hide yes)
			(effects
				(font
					(size 1.27 1.27)
					(thickness 0.15)
				)
			)
		)
		(property "Author" "Antmicro"
			(at 0 0 0)
			(layer "B.Fab")
			(hide yes)
			(effects
				(font
					(size 1 1)
					(thickness 0.15)
				)
				(justify mirror)
			)
		)
		(property "Dielectric" "X7R"
			(at 0 0 0)
			(layer "B.Fab")
			(hide yes)
			(effects
				(font
					(size 1 1)
					(thickness 0.15)
				)
				(justify mirror)
			)
		)
		(property "License" "Apache-2.0"
			(at 0 0 0)
			(layer "B.Fab")
			(hide yes)
			(effects
				(font
					(size 1 1)
					(thickness 0.15)
				)
				(justify mirror)
			)
		)
		(property "MPN" "W2A4YC104MAT2A"
			(at 0 0 0)
			(layer "B.Fab")
			(hide yes)
			(effects
				(font
					(size 1 1)
					(thickness 0.15)
				)
				(justify mirror)
			)
		)
		(property "Manufacturer" "KYOCERA AVX"
			(at 0 0 0)
			(layer "B.Fab")
			(hide yes)
			(effects
				(font
					(size 1 1)
					(thickness 0.15)
				)
				(justify mirror)
			)
		)
		(property "Val" "4x100nF"
			(at 0 0 0)
			(layer "B.Fab")
			(hide yes)
			(effects
				(font
					(size 1 1)
					(thickness 0.15)
				)
				(justify mirror)
			)
		)
		(property "Voltage" "16V"
			(at 0 0 0)
			(layer "B.Fab")
			(hide yes)
			(effects
				(font
					(size 1 1)
					(thickness 0.15)
				)
				(justify mirror)
			)
		)
		(sheetname "/PCIe/")
		(sheetfile "pcie.kicad_sch")
		(attr smd)
		(fp_circle
			(center -1.21 0.75)
			(end -1.16 0.75)
			(stroke
				(width 0.15)
				(type solid)
			)
			(fill yes)
			(layer "B.SilkS")
		)
		(fp_rect
			(start -1.09 1.2)
			(end 1.09 -1.2)
			(stroke
				(width 0.05)
				(type solid)
			)
			(fill no)
			(layer "B.CrtYd")
		)
		(fp_line
			(start -0.65 -1.05)
			(end -0.65 1.05)
			(stroke
				(width 0.15)
				(type solid)
			)
			(layer "B.Fab")
		)
		(fp_line
			(start -0.65 1.05)
			(end 0.65 1.05)
			(stroke
				(width 0.15)
				(type solid)
			)
			(layer "B.Fab")
		)
		(fp_line
			(start 0.65 -1.05)
			(end -0.65 -1.05)
			(stroke
				(width 0.15)
				(type solid)
			)
			(layer "B.Fab")
		)
		(fp_line
			(start 0.65 1.05)
			(end 0.65 -1.05)
			(stroke
				(width 0.15)
				(type solid)
			)
			(layer "B.Fab")
		)
		(fp_text user "${REFERENCE}"
			(at -1.26 -6 180)
			(layer "B.Fab")
			(effects
				(font
					(size 0.7 0.7)
					(thickness 0.15)
				)
				(justify left bottom mirror)
			)
		)
		(fp_text user "License: Apache-2.0"
			(at -1.26 -4.8 180)
			(layer "B.Fab")
			(effects
				(font
					(size 0.7 0.7)
					(thickness 0.15)
				)
				(justify left bottom mirror)
			)
		)
		(fp_text user "Author: Antmicro"
			(at -1.26 -7.2 180)
			(layer "B.Fab")
			(effects
				(font
					(size 0.7 0.7)
					(thickness 0.15)
				)
				(justify left bottom mirror)
			)
		)
		(pad "1" smd roundrect
			(at -0.66 0.75 90)
			(size 0.3 0.56)
			(layers "B.Cu" "B.Mask" "B.Paste")
			(roundrect_rratio 0.25)
			(net 19 "/Bottom Connector/PCIE.TXD0_P")
			(pinfunction "R1.1")
			(pintype "passive")
		)
		(pad "2" smd roundrect
			(at -0.66 0.25 90)
			(size 0.3 0.56)
			(layers "B.Cu" "B.Mask" "B.Paste")
			(roundrect_rratio 0.25)
			(net 33 "/Bottom Connector/PCIE.TXD0_N")
			(pinfunction "R2.1")
			(pintype "passive")
		)
		(pad "3" smd roundrect
			(at -0.66 -0.25 90)
			(size 0.3 0.56)
			(layers "B.Cu" "B.Mask" "B.Paste")
			(roundrect_rratio 0.25)
			(net 35 "/Bottom Connector/PCIE.TXD1_P")
			(pinfunction "R3.1")
			(pintype "passive")
		)
		(pad "4" smd roundrect
			(at -0.66 -0.75 90)
			(size 0.3 0.56)
			(layers "B.Cu" "B.Mask" "B.Paste")
			(roundrect_rratio 0.25)
			(net 36 "/Bottom Connector/PCIE.TXD1_N")
			(pinfunction "R4.1")
			(pintype "passive")
		)
		(pad "5" smd roundrect
			(at 0.66 -0.75 90)
			(size 0.3 0.56)
			(layers "B.Cu" "B.Mask" "B.Paste")
			(roundrect_rratio 0.25)
			(net 46 "/PCIe/XCVR_TX1_N")
			(pinfunction "R4.2")
			(pintype "passive")
		)
		(pad "6" smd roundrect
			(at 0.66 -0.25 90)
			(size 0.3 0.56)
			(layers "B.Cu" "B.Mask" "B.Paste")
			(roundrect_rratio 0.25)
			(net 51 "/PCIe/XCVR_TX1_P")
			(pinfunction "R3.2")
			(pintype "passive")
		)
		(pad "7" smd roundrect
			(at 0.66 0.25 90)
			(size 0.3 0.56)
			(layers "B.Cu" "B.Mask" "B.Paste")
			(roundrect_rratio 0.25)
			(net 53 "/PCIe/XCVR_TX0_N")
			(pinfunction "R2.2")
			(pintype "passive")
		)
		(pad "8" smd roundrect
			(at 0.66 0.75 90)
			(size 0.3 0.56)
			(layers "B.Cu" "B.Mask" "B.Paste")
			(roundrect_rratio 0.25)
			(net 64 "/PCIe/XCVR_TX0_P")
			(pinfunction "R1.2")
			(pintype "passive")
		)
	)
)
